FILE_TYPE = CONNECTIVITY;
{Allegro Design Entry HDL 17.4-2019 S026 (4007227) 1/17/2022}
"PAGE_NUMBER" = 43;
0"NC";
1"M_G_CPU1_SA_DQ<31:0>";
2"M_G_CPU1_SB_DQ<31:0>";
3"M_G_CPU1_SA_CB<7:0>";
4"M_G_CPU1_SB_CB<7:0>";
5"M_G_CPU1_SA_DQS_DN<9:0>";
6"M_G_CPU1_SA_DQS_DP<9:0>";
7"M_G_CPU1_SB_DQS_DP<9:0>";
8"M_G_CPU1_SB_DQS_DN<9:0>";
9"M_G_CPU1_SA_CA<6:0>";
10"M_G_CPU1_SB_CA<6:0>";
11"M_G_CPU1_ALERT_N";
12"M_G_CPU1_ALERT_R_N";
13"TP_M_G_CPU1_SA_TEST39G";
14"M_G_CPU1_CLK_DN<0>";
15"M_G_CPU1_CLK_DP<0>";
16"M_G_CPU1_SA_CS_N<0>";
17"M_G_CPU1_SA_CS_N<1>";
18"M_G_CPU1_SA_PAR";
19"M_G_CPU1_SA_RSP<0>";
20"M_G_CPU1_SB_CS_N<0>";
21"M_G_CPU1_SB_CS_N<1>";
22"M_G_CPU1_SB_RSP<0>";
23"M_G_CPU1_SB_PAR";
24"M_G_CPU1_RESET_N";
25"M_G_CPU1_SB_CA<6>";
26"M_G_CPU1_SA_CA<6>";
27"M_G_CPU1_SB_CA<5>";
28"M_G_CPU1_SA_CA<5>";
29"M_G_CPU1_SB_CA<4>";
30"M_G_CPU1_SA_CA<4>";
31"M_G_CPU1_SB_CA<3>";
32"M_G_CPU1_SA_CA<3>";
33"M_G_CPU1_SB_CA<2>";
34"M_G_CPU1_SA_CA<2>";
35"M_G_CPU1_SB_CA<1>";
36"M_G_CPU1_SA_CA<1>";
37"M_G_CPU1_SB_CA<0>";
38"M_G_CPU1_SA_CA<0>";
39"M_G_CPU1_SB_DQS_DN<9>";
40"M_G_CPU1_SB_DQS_DP<9>";
41"M_G_CPU1_SB_DQS_DP<4>";
42"M_G_CPU1_SB_DQS_DN<8>";
43"M_G_CPU1_SB_DQS_DP<3>";
44"M_G_CPU1_SB_DQS_DN<7>";
45"M_G_CPU1_SB_DQS_DP<2>";
46"M_G_CPU1_SB_DQS_DN<6>";
47"M_G_CPU1_SB_DQS_DP<1>";
48"M_G_CPU1_SB_DQS_DN<5>";
49"M_G_CPU1_SB_DQS_DP<0>";
50"M_G_CPU1_SB_DQS_DN<4>";
51"M_G_CPU1_SA_DQS_DN<9>";
52"M_G_CPU1_SB_DQS_DN<3>";
53"M_G_CPU1_SB_DQS_DN<2>";
54"M_G_CPU1_SB_DQS_DN<1>";
55"M_G_CPU1_SB_DQS_DN<0>";
56"M_G_CPU1_SB_DQS_DP<8>";
57"M_G_CPU1_SB_DQS_DP<7>";
58"M_G_CPU1_SB_DQS_DP<6>";
59"M_G_CPU1_SB_DQS_DP<5>";
60"M_G_CPU1_SA_DQS_DP<9>";
61"M_G_CPU1_SA_DQS_DP<8>";
62"M_G_CPU1_SA_DQS_DP<7>";
63"M_G_CPU1_SA_DQS_DP<6>";
64"M_G_CPU1_SA_DQS_DP<5>";
65"M_G_CPU1_SA_DQS_DP<4>";
66"M_G_CPU1_SA_DQS_DN<8>";
67"M_G_CPU1_SA_DQS_DP<3>";
68"M_G_CPU1_SA_DQS_DN<7>";
69"M_G_CPU1_SA_DQS_DP<2>";
70"M_G_CPU1_SA_DQS_DN<6>";
71"M_G_CPU1_SA_DQS_DP<1>";
72"M_G_CPU1_SA_DQS_DN<5>";
73"M_G_CPU1_SA_DQS_DP<0>";
74"M_G_CPU1_SA_DQS_DN<4>";
75"M_G_CPU1_SA_DQS_DN<3>";
76"M_G_CPU1_SA_DQS_DN<2>";
77"M_G_CPU1_SA_DQS_DN<1>";
78"M_G_CPU1_SA_DQS_DN<0>";
79"M_G_CPU1_SB_CB<7>";
80"M_G_CPU1_SB_CB<6>";
81"M_G_CPU1_SB_CB<5>";
82"M_G_CPU1_SB_CB<4>";
83"M_G_CPU1_SB_CB<3>";
84"M_G_CPU1_SB_CB<2>";
85"M_G_CPU1_SB_CB<1>";
86"M_G_CPU1_SB_CB<0>";
87"M_G_CPU1_SA_CB<1>";
88"M_G_CPU1_SA_CB<0>";
89"M_G_CPU1_SB_DQ<29>";
90"M_G_CPU1_SB_DQ<28>";
91"M_G_CPU1_SB_DQ<27>";
92"M_G_CPU1_SB_DQ<26>";
93"M_G_CPU1_SB_DQ<25>";
94"M_G_CPU1_SB_DQ<24>";
95"M_G_CPU1_SB_DQ<23>";
96"M_G_CPU1_SB_DQ<22>";
97"M_G_CPU1_SA_CB<7>";
98"M_G_CPU1_SA_CB<6>";
99"M_G_CPU1_SB_DQ<31>";
100"M_G_CPU1_SA_CB<5>";
101"M_G_CPU1_SB_DQ<30>";
102"M_G_CPU1_SA_CB<4>";
103"M_G_CPU1_SA_CB<3>";
104"M_G_CPU1_SA_CB<2>";
105"M_G_CPU1_SB_DQ<19>";
106"M_G_CPU1_SB_DQ<18>";
107"M_G_CPU1_SB_DQ<17>";
108"M_G_CPU1_SB_DQ<16>";
109"M_G_CPU1_SB_DQ<15>";
110"M_G_CPU1_SB_DQ<14>";
111"M_G_CPU1_SB_DQ<9>";
112"M_G_CPU1_SB_DQ<13>";
113"M_G_CPU1_SB_DQ<8>";
114"M_G_CPU1_SB_DQ<12>";
115"M_G_CPU1_SB_DQ<7>";
116"M_G_CPU1_SB_DQ<11>";
117"M_G_CPU1_SB_DQ<6>";
118"M_G_CPU1_SB_DQ<10>";
119"M_G_CPU1_SB_DQ<21>";
120"M_G_CPU1_SB_DQ<5>";
121"M_G_CPU1_SB_DQ<20>";
122"M_G_CPU1_SB_DQ<4>";
123"M_G_CPU1_SA_DQ<21>";
124"M_G_CPU1_SB_DQ<0>";
125"M_G_CPU1_SA_DQ<20>";
126"M_G_CPU1_SA_DQ<31>";
127"M_G_CPU1_SA_DQ<30>";
128"M_G_CPU1_SA_DQ<19>";
129"M_G_CPU1_SA_DQ<18>";
130"M_G_CPU1_SA_DQ<29>";
131"M_G_CPU1_SA_DQ<17>";
132"M_G_CPU1_SA_DQ<28>";
133"M_G_CPU1_SA_DQ<27>";
134"M_G_CPU1_SA_DQ<26>";
135"M_G_CPU1_SA_DQ<25>";
136"M_G_CPU1_SA_DQ<24>";
137"M_G_CPU1_SB_DQ<3>";
138"M_G_CPU1_SA_DQ<23>";
139"M_G_CPU1_SB_DQ<2>";
140"M_G_CPU1_SA_DQ<22>";
141"M_G_CPU1_SB_DQ<1>";
142"M_G_CPU1_SA_DQ<0>";
143"M_G_CPU1_SA_DQ<10>";
144"M_G_CPU1_SA_DQ<9>";
145"M_G_CPU1_SA_DQ<8>";
146"M_G_CPU1_SA_DQ<7>";
147"M_G_CPU1_SA_DQ<6>";
148"M_G_CPU1_SA_DQ<16>";
149"M_G_CPU1_SA_DQ<5>";
150"M_G_CPU1_SA_DQ<15>";
151"M_G_CPU1_SA_DQ<4>";
152"M_G_CPU1_SA_DQ<14>";
153"M_G_CPU1_SA_DQ<3>";
154"M_G_CPU1_SA_DQ<13>";
155"M_G_CPU1_SA_DQ<2>";
156"M_G_CPU1_SA_DQ<12>";
157"M_G_CPU1_SA_DQ<1>";
158"M_G_CPU1_SA_DQ<11>";
%"GENOA_SP5"
"7","(-4700,3675)","0","pure_quanta","I167";
;
LOCATION"U26"
$SEC"7"
CDS_SEC"7"
PART_TYPE"SMLF"
MATERIAL"IO"
VALUE"SOCKET6096_13568-001"
NEEDS_NO_SIZE"TRUE"
CDS_LMAN_SYM_OUTLINE"-650,2525,650,-2525"
CDS_LIB"pure_quanta"
PART_NUMBER"DGA^6000030";
"TEST39G"
$PN"BF4"13;
"MG1_CLK_L"
$PN"BG2"0;
"MG1_CLK_H"
$PN"BF2"0;
"MG0_CLK_L"
$PN"BD2"14;
"MG0_CLK_H"
$PN"BC2"15;
"MGA_PAR"
$PN"BC3"18;
"MGB_DQS_H9"
$PN"BV2"40;
"MGB_PAR"
$PN"BL3"23;
"MGA_CHECK1"
$PN"AK4"87;
"MGA_DATA0"
$PN"E2"142;
"MGA_DATA10"
$PN"M2"143;
"MGA_DATA21"
$PN"AB4"123;
"MGB_DATA0"
$PN"CB2"124;
"MGB_DQS_H4"
$PN"BY4"41;
"MGB_DQS_L8"
$PN"DC3"42;
"MGA_CHECK0"
$PN"AJ2"88;
"MGA_DATA20"
$PN"AA2"125;
"MGA_DATA31"
$PN"AJ3"126;
"MGA_DQS_H9"
$PN"AN3"60;
"MGB_DQS_H3"
$PN"DB2"43;
"MGB_DQS_L7"
$PN"CU3"44;
"MGA0_CS_L1"
$PN"AV4"17;
"MGA1_CS_L1"
$PN"AW3"0;
"MGA_DATA30"
$PN"AH2"127;
"MGA_DQS_H8"
$PN"AG3"61;
"MGB_DATA19"
$PN"CT4"105;
"MGB_DQS_H2"
$PN"CT2"45;
"MGB_DQS_L6"
$PN"CL3"46;
"MGA0_CS_L0"
$PN"AU2"16;
"MGA1_CS_L0"
$PN"AV2"0;
"MGA_DQS_H7"
$PN"AA3"62;
"MGB_DATA18"
$PN"CR2"106;
"MGB_DATA29"
$PN"DE3"89;
"MGB_DQS_H1"
$PN"CK2"47;
"MGB_DQS_L5"
$PN"CE3"48;
"MGA_DQS_H6"
$PN"R3"63;
"MGB_DATA17"
$PN"CR3"107;
"MGB_DATA28"
$PN"DD2"90;
"MGB_DQS_H0"
$PN"CD2"49;
"MGB_DQS_L4"
$PN"BW3"50;
"MGA_DQS_H5"
$PN"J3"64;
"MGA_DQS_L9"
$PN"AM4"51;
"MGB0_RSP_L"
$PN"BP2"22;
"MGB1_RSP_L"
$PN"BR2"0;
"MGB_CHECK7"
$PN"BV4"79;
"MGB_DATA16"
$PN"CP2"108;
"MGB_DATA27"
$PN"DB4"91;
"MGB_DQS_L3"
$PN"DC2"52;
"MGA_DQS_H4"
$PN"AL2"65;
"MGA_DQS_L8"
$PN"AF4"66;
"MGB_CA6"
$PN"BK2"25;
"MGB_CHECK6"
$PN"BU2"80;
"MGB_DATA15"
$PN"CP4"109;
"MGB_DATA26"
$PN"DA2"92;
"MGB_DQS_L2"
$PN"CU2"53;
"MGA_CA6"
$PN"BB4"26;
"MGA_DQS_H3"
$PN"AE2"67;
"MGA_DQS_L7"
$PN"Y4"68;
"MGB_CA5"
$PN"BK4"27;
"MGB_CHECK5"
$PN"BU3"81;
"MGB_DATA14"
$PN"CN2"110;
"MGB_DATA25"
$PN"DA3"93;
"MGB_DQS_L1"
$PN"CL2"54;
"MGA_CA5"
$PN"BB2"28;
"MGA_DATA9"
$PN"M4"144;
"MGA_DATA19"
$PN"W3"128;
"MGA_DQS_H2"
$PN"W2"69;
"MGA_DQS_L6"
$PN"P4"70;
"MGB_CA4"
$PN"BJ3"29;
"MGB_CHECK4"
$PN"BT2"82;
"MGB_DATA9"
$PN"CJ3"111;
"MGB_DATA13"
$PN"CN3"112;
"MGB_DATA24"
$PN"CY2"94;
"MGB_DQS_L0"
$PN"CE2"55;
"MGA_CA4"
$PN"BA2"30;
"MGA_DATA8"
$PN"L2"145;
"MGA_DATA18"
$PN"V2"129;
"MGA_DATA29"
$PN"AH4"130;
"MGA_DQS_H1"
$PN"N2"71;
"MGA_DQS_L5"
$PN"H4"72;
"MGB_CA3"
$PN"BJ2"31;
"MGB_CHECK3"
$PN"CB4"83;
"MGB_DATA8"
$PN"CH2"113;
"MGB_DATA12"
$PN"CM2"114;
"MGB_DATA23"
$PN"CY4"95;
"MGA_CA3"
$PN"BA3"32;
"MGA_DATA7"
$PN"L3"146;
"MGA_DATA17"
$PN"V4"131;
"MGA_DATA28"
$PN"AG2"132;
"MGA_DQS_H0"
$PN"G2"73;
"MGA_DQS_L4"
$PN"AM2"74;
"MGB_CA2"
$PN"BH2"33;
"MGB_CHECK2"
$PN"CA2"84;
"MGB_DATA7"
$PN"CH4"115;
"MGB_DATA11"
$PN"CK4"116;
"MGB_DATA22"
$PN"CW2"96;
"MGA0_RSP_L"
$PN"BN3"19;
"MGA1_RSP_L"
$PN"BP4"0;
"MGA_CA2"
$PN"AY4"34;
"MGA_CHECK7"
$PN"AR3"97;
"MGA_DATA6"
$PN"K2"147;
"MGA_DATA16"
$PN"U2"148;
"MGA_DATA27"
$PN"AE3"133;
"MGA_DQS_L3"
$PN"AF2"75;
"MGB_CA1"
$PN"BH4"35;
"MGB_CHECK1"
$PN"CA3"85;
"MGB_DATA6"
$PN"CG2"117;
"MGB_DATA10"
$PN"CJ2"118;
"MGB_DATA21"
$PN"CW3"119;
"MGA_CA1"
$PN"AY2"36;
"MGA_CHECK6"
$PN"AP2"98;
"MGA_DATA5"
$PN"K4"149;
"MGA_DATA15"
$PN"U3"150;
"MGA_DATA26"
$PN"AD2"134;
"MGA_DQS_L2"
$PN"Y2"76;
"MGB_CA0"
$PN"BG3"37;
"MGB_CHECK0"
$PN"BY2"86;
"MGB_DATA5"
$PN"CG3"120;
"MGB_DATA20"
$PN"CV2"121;
"MGB_DATA31"
$PN"DF2"99;
"MGA_CA0"
$PN"AW2"38;
"MGA_CHECK5"
$PN"AP4"100;
"MGA_DATA4"
$PN"J2"151;
"MGA_DATA14"
$PN"T2"152;
"MGA_DATA25"
$PN"AD4"135;
"MGA_DQS_L1"
$PN"P2"77;
"MGB0_CS_L1"
$PN"BN2"21;
"MGB1_CS_L1"
$PN"BM2"0;
"MGB_DATA4"
$PN"CF2"122;
"MGB_DATA30"
$PN"DE2"101;
"MGB_DQS_H8"
$PN"DD4"56;
"MGA_CHECK4"
$PN"AN2"102;
"MGA_DATA3"
$PN"G3"153;
"MGA_DATA13"
$PN"T4"154;
"MGA_DATA24"
$PN"AC2"136;
"MGA_DQS_L0"
$PN"H2"78;
"MGB0_CS_L0"
$PN"BM4"20;
"MGB1_CS_L0"
$PN"BL2"0;
"MGB_DATA3"
$PN"CD4"137;
"MGB_DQS_H7"
$PN"CV4"57;
"MGA_CHECK3"
$PN"AL3"103;
"MGA_DATA2"
$PN"F2"155;
"MGA_DATA12"
$PN"R2"156;
"MGA_DATA23"
$PN"AC3"138;
"MGB_DATA2"
$PN"CC2"139;
"MGB_DQS_H6"
$PN"CM4"58;
"MGA_CHECK2"
$PN"AK2"104;
"MGA_DATA1"
$PN"F4"157;
"MGA_DATA11"
$PN"N3"158;
"MGA_DATA22"
$PN"AB2"140;
"MGB_DATA1"
$PN"CC3"141;
"MGB_DQS_H5"
$PN"CF4"59;
"MGB_DQS_L9"
$PN"BW2"39;
"MG_RESET_L"
$PN"AT2"24;
"MG_ALERT_L"
$PN"AR2"12;
%"TAP"
"1","(-3425,6050)","0","mstr_standard","I170";
;
CDS_LIB"mstr_standard"
BODY_TYPE"PLUMBING"
HDL_TAP"TRUE";
"B \NAC \NWC"1;
"S \NAC"
BN"0"142;
%"TAP"
"1","(-3425,6000)","0","mstr_standard","I171";
;
CDS_LIB"mstr_standard"
BODY_TYPE"PLUMBING"
HDL_TAP"TRUE";
"B \NAC \NWC"1;
"S \NAC"
BN"1"157;
%"TAP"
"1","(-3425,5900)","0","mstr_standard","I172";
;
CDS_LIB"mstr_standard"
BODY_TYPE"PLUMBING"
HDL_TAP"TRUE";
"B \NAC \NWC"1;
"S \NAC"
BN"3"153;
%"TAP"
"1","(-3425,5950)","0","mstr_standard","I173";
;
CDS_LIB"mstr_standard"
BODY_TYPE"PLUMBING"
HDL_TAP"TRUE";
"B \NAC \NWC"1;
"S \NAC"
BN"2"155;
%"TAP"
"1","(-3425,5850)","0","mstr_standard","I174";
;
CDS_LIB"mstr_standard"
BODY_TYPE"PLUMBING"
HDL_TAP"TRUE";
"B \NAC \NWC"1;
"S \NAC"
BN"4"151;
%"TAP"
"1","(-3425,5800)","0","mstr_standard","I175";
;
CDS_LIB"mstr_standard"
BODY_TYPE"PLUMBING"
HDL_TAP"TRUE";
"B \NAC \NWC"1;
"S \NAC"
BN"5"149;
%"TAP"
"1","(-3425,5750)","0","mstr_standard","I176";
;
CDS_LIB"mstr_standard"
BODY_TYPE"PLUMBING"
HDL_TAP"TRUE";
"B \NAC \NWC"1;
"S \NAC"
BN"6"147;
%"TAP"
"1","(-3425,5700)","0","mstr_standard","I177";
;
CDS_LIB"mstr_standard"
BODY_TYPE"PLUMBING"
HDL_TAP"TRUE";
"B \NAC \NWC"1;
"S \NAC"
BN"7"146;
%"TAP"
"1","(-3425,5600)","0","mstr_standard","I178";
;
CDS_LIB"mstr_standard"
BODY_TYPE"PLUMBING"
HDL_TAP"TRUE";
"B \NAC \NWC"1;
"S \NAC"
BN"8"145;
%"TAP"
"1","(-3425,5550)","0","mstr_standard","I179";
;
CDS_LIB"mstr_standard"
BODY_TYPE"PLUMBING"
HDL_TAP"TRUE";
"B \NAC \NWC"1;
"S \NAC"
BN"9"144;
%"TAP"
"1","(-3425,5500)","0","mstr_standard","I180";
;
CDS_LIB"mstr_standard"
BODY_TYPE"PLUMBING"
HDL_TAP"TRUE";
"B \NAC \NWC"1;
"S \NAC"
BN"10"143;
%"TAP"
"1","(-3425,5450)","0","mstr_standard","I181";
;
CDS_LIB"mstr_standard"
BODY_TYPE"PLUMBING"
HDL_TAP"TRUE";
"B \NAC \NWC"1;
"S \NAC"
BN"11"158;
%"TAP"
"1","(-3425,5400)","0","mstr_standard","I182";
;
CDS_LIB"mstr_standard"
BODY_TYPE"PLUMBING"
HDL_TAP"TRUE";
"B \NAC \NWC"1;
"S \NAC"
BN"12"156;
%"TAP"
"1","(-3425,5350)","0","mstr_standard","I183";
;
CDS_LIB"mstr_standard"
BODY_TYPE"PLUMBING"
HDL_TAP"TRUE";
"B \NAC \NWC"1;
"S \NAC"
BN"13"154;
%"TAP"
"1","(-3425,5250)","0","mstr_standard","I184";
;
CDS_LIB"mstr_standard"
BODY_TYPE"PLUMBING"
HDL_TAP"TRUE";
"B \NAC \NWC"1;
"S \NAC"
BN"15"150;
%"TAP"
"1","(-3425,5300)","0","mstr_standard","I185";
;
CDS_LIB"mstr_standard"
BODY_TYPE"PLUMBING"
HDL_TAP"TRUE";
"B \NAC \NWC"1;
"S \NAC"
BN"14"152;
%"TAP"
"1","(-3425,5150)","0","mstr_standard","I186";
;
CDS_LIB"mstr_standard"
BODY_TYPE"PLUMBING"
HDL_TAP"TRUE";
"B \NAC \NWC"1;
"S \NAC"
BN"16"148;
%"TAP"
"1","(-3425,5100)","0","mstr_standard","I187";
;
CDS_LIB"mstr_standard"
BODY_TYPE"PLUMBING"
HDL_TAP"TRUE";
"B \NAC \NWC"1;
"S \NAC"
BN"17"131;
%"TAP"
"1","(-3425,5000)","0","mstr_standard","I188";
;
CDS_LIB"mstr_standard"
BODY_TYPE"PLUMBING"
HDL_TAP"TRUE";
"B \NAC \NWC"1;
"S \NAC"
BN"19"128;
%"TAP"
"1","(-3425,5050)","0","mstr_standard","I189";
;
CDS_LIB"mstr_standard"
BODY_TYPE"PLUMBING"
HDL_TAP"TRUE";
"B \NAC \NWC"1;
"S \NAC"
BN"18"129;
%"TAP"
"1","(-3425,4950)","0","mstr_standard","I190";
;
CDS_LIB"mstr_standard"
BODY_TYPE"PLUMBING"
HDL_TAP"TRUE";
"B \NAC \NWC"1;
"S \NAC"
BN"20"125;
%"TAP"
"1","(-3425,4900)","0","mstr_standard","I191";
;
CDS_LIB"mstr_standard"
BODY_TYPE"PLUMBING"
HDL_TAP"TRUE";
"B \NAC \NWC"1;
"S \NAC"
BN"21"123;
%"TAP"
"1","(-3425,4850)","0","mstr_standard","I192";
;
CDS_LIB"mstr_standard"
BODY_TYPE"PLUMBING"
HDL_TAP"TRUE";
"B \NAC \NWC"1;
"S \NAC"
BN"22"140;
%"TAP"
"1","(-3425,4800)","0","mstr_standard","I193";
;
CDS_LIB"mstr_standard"
BODY_TYPE"PLUMBING"
HDL_TAP"TRUE";
"B \NAC \NWC"1;
"S \NAC"
BN"23"138;
%"TAP"
"1","(-3425,4700)","0","mstr_standard","I194";
;
CDS_LIB"mstr_standard"
BODY_TYPE"PLUMBING"
HDL_TAP"TRUE";
"B \NAC \NWC"1;
"S \NAC"
BN"24"136;
%"TAP"
"1","(-3425,4650)","0","mstr_standard","I195";
;
CDS_LIB"mstr_standard"
BODY_TYPE"PLUMBING"
HDL_TAP"TRUE";
"B \NAC \NWC"1;
"S \NAC"
BN"25"135;
%"TAP"
"1","(-3425,4600)","0","mstr_standard","I196";
;
CDS_LIB"mstr_standard"
BODY_TYPE"PLUMBING"
HDL_TAP"TRUE";
"B \NAC \NWC"1;
"S \NAC"
BN"26"134;
%"TAP"
"1","(-3425,4550)","0","mstr_standard","I197";
;
CDS_LIB"mstr_standard"
BODY_TYPE"PLUMBING"
HDL_TAP"TRUE";
"B \NAC \NWC"1;
"S \NAC"
BN"27"133;
%"TAP"
"1","(-3425,4500)","0","mstr_standard","I198";
;
CDS_LIB"mstr_standard"
BODY_TYPE"PLUMBING"
HDL_TAP"TRUE";
"B \NAC \NWC"1;
"S \NAC"
BN"28"132;
%"TAP"
"1","(-3425,4450)","0","mstr_standard","I199";
;
CDS_LIB"mstr_standard"
BODY_TYPE"PLUMBING"
HDL_TAP"TRUE";
"B \NAC \NWC"1;
"S \NAC"
BN"29"130;
%"TAP"
"1","(-3425,4400)","0","mstr_standard","I200";
;
CDS_LIB"mstr_standard"
BODY_TYPE"PLUMBING"
HDL_TAP"TRUE";
"B \NAC \NWC"1;
"S \NAC"
BN"30"127;
%"TAP"
"1","(-3425,4350)","0","mstr_standard","I201";
;
CDS_LIB"mstr_standard"
BODY_TYPE"PLUMBING"
HDL_TAP"TRUE";
"B \NAC \NWC"1;
"S \NAC"
BN"31"126;
%"TAP"
"1","(-3425,4250)","0","mstr_standard","I202";
;
CDS_LIB"mstr_standard"
BODY_TYPE"PLUMBING"
HDL_TAP"TRUE";
"B \NAC \NWC"2;
"S \NAC"
BN"0"124;
%"TAP"
"1","(-3425,4200)","0","mstr_standard","I203";
;
CDS_LIB"mstr_standard"
BODY_TYPE"PLUMBING"
HDL_TAP"TRUE";
"B \NAC \NWC"2;
"S \NAC"
BN"1"141;
%"TAP"
"1","(-3425,4100)","0","mstr_standard","I204";
;
CDS_LIB"mstr_standard"
BODY_TYPE"PLUMBING"
HDL_TAP"TRUE";
"B \NAC \NWC"2;
"S \NAC"
BN"3"137;
%"TAP"
"1","(-3425,4150)","0","mstr_standard","I205";
;
CDS_LIB"mstr_standard"
BODY_TYPE"PLUMBING"
HDL_TAP"TRUE";
"B \NAC \NWC"2;
"S \NAC"
BN"2"139;
%"TAP"
"1","(-3425,4050)","0","mstr_standard","I207";
;
CDS_LIB"mstr_standard"
BODY_TYPE"PLUMBING"
HDL_TAP"TRUE";
"B \NAC \NWC"2;
"S \NAC"
BN"4"122;
%"TAP"
"1","(-3425,4000)","0","mstr_standard","I208";
;
CDS_LIB"mstr_standard"
BODY_TYPE"PLUMBING"
HDL_TAP"TRUE";
"B \NAC \NWC"2;
"S \NAC"
BN"5"120;
%"TAP"
"1","(-3425,3950)","0","mstr_standard","I209";
;
CDS_LIB"mstr_standard"
BODY_TYPE"PLUMBING"
HDL_TAP"TRUE";
"B \NAC \NWC"2;
"S \NAC"
BN"6"117;
%"TAP"
"1","(-3425,3900)","0","mstr_standard","I210";
;
CDS_LIB"mstr_standard"
BODY_TYPE"PLUMBING"
HDL_TAP"TRUE";
"B \NAC \NWC"2;
"S \NAC"
BN"7"115;
%"TAP"
"1","(-3425,3800)","0","mstr_standard","I211";
;
CDS_LIB"mstr_standard"
BODY_TYPE"PLUMBING"
HDL_TAP"TRUE";
"B \NAC \NWC"2;
"S \NAC"
BN"8"113;
%"TAP"
"1","(-3425,3750)","0","mstr_standard","I212";
;
CDS_LIB"mstr_standard"
BODY_TYPE"PLUMBING"
HDL_TAP"TRUE";
"B \NAC \NWC"2;
"S \NAC"
BN"9"111;
%"TAP"
"1","(-3425,3700)","0","mstr_standard","I213";
;
CDS_LIB"mstr_standard"
BODY_TYPE"PLUMBING"
HDL_TAP"TRUE";
"B \NAC \NWC"2;
"S \NAC"
BN"10"118;
%"TAP"
"1","(-3425,3650)","0","mstr_standard","I214";
;
CDS_LIB"mstr_standard"
BODY_TYPE"PLUMBING"
HDL_TAP"TRUE";
"B \NAC \NWC"2;
"S \NAC"
BN"11"116;
%"TAP"
"1","(-3425,3600)","0","mstr_standard","I215";
;
CDS_LIB"mstr_standard"
BODY_TYPE"PLUMBING"
HDL_TAP"TRUE";
"B \NAC \NWC"2;
"S \NAC"
BN"12"114;
%"TAP"
"1","(-3425,3550)","0","mstr_standard","I216";
;
CDS_LIB"mstr_standard"
BODY_TYPE"PLUMBING"
HDL_TAP"TRUE";
"B \NAC \NWC"2;
"S \NAC"
BN"13"112;
%"TAP"
"1","(-3425,3500)","0","mstr_standard","I217";
;
CDS_LIB"mstr_standard"
BODY_TYPE"PLUMBING"
HDL_TAP"TRUE";
"B \NAC \NWC"2;
"S \NAC"
BN"14"110;
%"TAP"
"1","(-3425,3450)","0","mstr_standard","I218";
;
CDS_LIB"mstr_standard"
BODY_TYPE"PLUMBING"
HDL_TAP"TRUE";
"B \NAC \NWC"2;
"S \NAC"
BN"15"109;
%"TAP"
"1","(-3425,3350)","0","mstr_standard","I219";
;
CDS_LIB"mstr_standard"
BODY_TYPE"PLUMBING"
HDL_TAP"TRUE";
"B \NAC \NWC"2;
"S \NAC"
BN"16"108;
%"TAP"
"1","(-3425,3300)","0","mstr_standard","I220";
;
CDS_LIB"mstr_standard"
BODY_TYPE"PLUMBING"
HDL_TAP"TRUE";
"B \NAC \NWC"2;
"S \NAC"
BN"17"107;
%"TAP"
"1","(-3425,3250)","0","mstr_standard","I221";
;
CDS_LIB"mstr_standard"
BODY_TYPE"PLUMBING"
HDL_TAP"TRUE";
"B \NAC \NWC"2;
"S \NAC"
BN"18"106;
%"TAP"
"1","(-3425,3200)","0","mstr_standard","I222";
;
CDS_LIB"mstr_standard"
BODY_TYPE"PLUMBING"
HDL_TAP"TRUE";
"B \NAC \NWC"2;
"S \NAC"
BN"19"105;
%"TAP"
"1","(-3425,3150)","0","mstr_standard","I223";
;
CDS_LIB"mstr_standard"
BODY_TYPE"PLUMBING"
HDL_TAP"TRUE";
"B \NAC \NWC"2;
"S \NAC"
BN"20"121;
%"TAP"
"1","(-3425,3100)","0","mstr_standard","I224";
;
CDS_LIB"mstr_standard"
BODY_TYPE"PLUMBING"
HDL_TAP"TRUE";
"B \NAC \NWC"2;
"S \NAC"
BN"21"119;
%"TAP"
"1","(-3425,3000)","0","mstr_standard","I225";
;
CDS_LIB"mstr_standard"
BODY_TYPE"PLUMBING"
HDL_TAP"TRUE";
"B \NAC \NWC"2;
"S \NAC"
BN"23"95;
%"TAP"
"1","(-3425,3050)","0","mstr_standard","I226";
;
CDS_LIB"mstr_standard"
BODY_TYPE"PLUMBING"
HDL_TAP"TRUE";
"B \NAC \NWC"2;
"S \NAC"
BN"22"96;
%"TAP"
"1","(-3425,2900)","0","mstr_standard","I227";
;
CDS_LIB"mstr_standard"
BODY_TYPE"PLUMBING"
HDL_TAP"TRUE";
"B \NAC \NWC"2;
"S \NAC"
BN"24"94;
%"TAP"
"1","(-3425,2850)","0","mstr_standard","I228";
;
CDS_LIB"mstr_standard"
BODY_TYPE"PLUMBING"
HDL_TAP"TRUE";
"B \NAC \NWC"2;
"S \NAC"
BN"25"93;
%"TAP"
"1","(-3425,2800)","0","mstr_standard","I229";
;
CDS_LIB"mstr_standard"
BODY_TYPE"PLUMBING"
HDL_TAP"TRUE";
"B \NAC \NWC"2;
"S \NAC"
BN"26"92;
%"TAP"
"1","(-3425,2700)","0","mstr_standard","I230";
;
CDS_LIB"mstr_standard"
BODY_TYPE"PLUMBING"
HDL_TAP"TRUE";
"B \NAC \NWC"2;
"S \NAC"
BN"28"90;
%"TAP"
"1","(-3425,2750)","0","mstr_standard","I231";
;
CDS_LIB"mstr_standard"
BODY_TYPE"PLUMBING"
HDL_TAP"TRUE";
"B \NAC \NWC"2;
"S \NAC"
BN"27"91;
%"TAP"
"1","(-3425,2650)","0","mstr_standard","I232";
;
CDS_LIB"mstr_standard"
BODY_TYPE"PLUMBING"
HDL_TAP"TRUE";
"B \NAC \NWC"2;
"S \NAC"
BN"29"89;
%"TAP"
"1","(-3425,2600)","0","mstr_standard","I233";
;
CDS_LIB"mstr_standard"
BODY_TYPE"PLUMBING"
HDL_TAP"TRUE";
"B \NAC \NWC"2;
"S \NAC"
BN"30"101;
%"TAP"
"1","(-3425,2550)","0","mstr_standard","I234";
;
CDS_LIB"mstr_standard"
BODY_TYPE"PLUMBING"
HDL_TAP"TRUE";
"B \NAC \NWC"2;
"S \NAC"
BN"31"99;
%"TAP"
"1","(-3425,2450)","0","mstr_standard","I235";
;
CDS_LIB"mstr_standard"
BODY_TYPE"PLUMBING"
HDL_TAP"TRUE";
"B \NAC \NWC"3;
"S \NAC"
BN"0"88;
%"TAP"
"1","(-3425,2400)","0","mstr_standard","I236";
;
CDS_LIB"mstr_standard"
BODY_TYPE"PLUMBING"
HDL_TAP"TRUE";
"B \NAC \NWC"3;
"S \NAC"
BN"1"87;
%"TAP"
"1","(-3425,2350)","0","mstr_standard","I237";
;
CDS_LIB"mstr_standard"
BODY_TYPE"PLUMBING"
HDL_TAP"TRUE";
"B \NAC \NWC"3;
"S \NAC"
BN"2"104;
%"TAP"
"1","(-3425,2300)","0","mstr_standard","I238";
;
CDS_LIB"mstr_standard"
BODY_TYPE"PLUMBING"
HDL_TAP"TRUE";
"B \NAC \NWC"3;
"S \NAC"
BN"3"103;
%"TAP"
"1","(-3425,2250)","0","mstr_standard","I239";
;
CDS_LIB"mstr_standard"
BODY_TYPE"PLUMBING"
HDL_TAP"TRUE";
"B \NAC \NWC"3;
"S \NAC"
BN"4"102;
%"TAP"
"1","(-3425,2200)","0","mstr_standard","I240";
;
CDS_LIB"mstr_standard"
BODY_TYPE"PLUMBING"
HDL_TAP"TRUE";
"B \NAC \NWC"3;
"S \NAC"
BN"5"100;
%"TAP"
"1","(-3425,2150)","0","mstr_standard","I241";
;
CDS_LIB"mstr_standard"
BODY_TYPE"PLUMBING"
HDL_TAP"TRUE";
"B \NAC \NWC"3;
"S \NAC"
BN"6"98;
%"TAP"
"1","(-3425,2100)","0","mstr_standard","I242";
;
CDS_LIB"mstr_standard"
BODY_TYPE"PLUMBING"
HDL_TAP"TRUE";
"B \NAC \NWC"3;
"S \NAC"
BN"7"97;
%"TAP"
"1","(-3425,1950)","0","mstr_standard","I244";
;
CDS_LIB"mstr_standard"
BODY_TYPE"PLUMBING"
HDL_TAP"TRUE";
"B \NAC \NWC"4;
"S \NAC"
BN"1"85;
%"TAP"
"1","(-3425,2000)","0","mstr_standard","I245";
;
CDS_LIB"mstr_standard"
BODY_TYPE"PLUMBING"
HDL_TAP"TRUE";
"B \NAC \NWC"4;
"S \NAC"
BN"0"86;
%"TAP"
"1","(-3425,1900)","0","mstr_standard","I246";
;
CDS_LIB"mstr_standard"
BODY_TYPE"PLUMBING"
HDL_TAP"TRUE";
"B \NAC \NWC"4;
"S \NAC"
BN"2"84;
%"TAP"
"1","(-3425,1800)","0","mstr_standard","I247";
;
CDS_LIB"mstr_standard"
BODY_TYPE"PLUMBING"
HDL_TAP"TRUE";
"B \NAC \NWC"4;
"S \NAC"
BN"4"82;
%"TAP"
"1","(-3425,1850)","0","mstr_standard","I248";
;
CDS_LIB"mstr_standard"
BODY_TYPE"PLUMBING"
HDL_TAP"TRUE";
"B \NAC \NWC"4;
"S \NAC"
BN"3"83;
%"TAP"
"1","(-3425,1700)","0","mstr_standard","I249";
;
CDS_LIB"mstr_standard"
BODY_TYPE"PLUMBING"
HDL_TAP"TRUE";
"B \NAC \NWC"4;
"S \NAC"
BN"6"80;
%"TAP"
"1","(-3425,1750)","0","mstr_standard","I250";
;
CDS_LIB"mstr_standard"
BODY_TYPE"PLUMBING"
HDL_TAP"TRUE";
"B \NAC \NWC"4;
"S \NAC"
BN"5"81;
%"TAP"
"1","(-3425,1650)","0","mstr_standard","I251";
;
CDS_LIB"mstr_standard"
BODY_TYPE"PLUMBING"
HDL_TAP"TRUE";
"B \NAC \NWC"4;
"S \NAC"
BN"7"79;
%"TAP"
"1","(-5850,6050)","2","mstr_standard","I252";
;
CDS_LIB"mstr_standard"
BODY_TYPE"PLUMBING"
HDL_TAP"TRUE";
"B \NAC \NWC"6;
"S \NAC"
BN"0"73;
%"TAP"
"1","(-5850,5950)","2","mstr_standard","I253";
;
CDS_LIB"mstr_standard"
BODY_TYPE"PLUMBING"
HDL_TAP"TRUE";
"B \NAC \NWC"6;
"S \NAC"
BN"1"71;
%"TAP"
"1","(-5850,5850)","2","mstr_standard","I254";
;
CDS_LIB"mstr_standard"
BODY_TYPE"PLUMBING"
HDL_TAP"TRUE";
"B \NAC \NWC"6;
"S \NAC"
BN"2"69;
%"TAP"
"1","(-5850,5750)","2","mstr_standard","I255";
;
CDS_LIB"mstr_standard"
BODY_TYPE"PLUMBING"
HDL_TAP"TRUE";
"B \NAC \NWC"6;
"S \NAC"
BN"3"67;
%"TAP"
"1","(-5850,5650)","2","mstr_standard","I256";
;
CDS_LIB"mstr_standard"
BODY_TYPE"PLUMBING"
HDL_TAP"TRUE";
"B \NAC \NWC"6;
"S \NAC"
BN"4"65;
%"TAP"
"1","(-6050,6000)","2","mstr_standard","I257";
;
CDS_LIB"mstr_standard"
BODY_TYPE"PLUMBING"
HDL_TAP"TRUE";
"B \NAC \NWC"5;
"S \NAC"
BN"0"78;
%"TAP"
"1","(-6050,5900)","2","mstr_standard","I258";
;
CDS_LIB"mstr_standard"
BODY_TYPE"PLUMBING"
HDL_TAP"TRUE";
"B \NAC \NWC"5;
"S \NAC"
BN"1"77;
%"TAP"
"1","(-6050,5800)","2","mstr_standard","I259";
;
CDS_LIB"mstr_standard"
BODY_TYPE"PLUMBING"
HDL_TAP"TRUE";
"B \NAC \NWC"5;
"S \NAC"
BN"2"76;
%"TAP"
"1","(-6050,5700)","2","mstr_standard","I260";
;
CDS_LIB"mstr_standard"
BODY_TYPE"PLUMBING"
HDL_TAP"TRUE";
"B \NAC \NWC"5;
"S \NAC"
BN"3"75;
%"TAP"
"1","(-5850,5550)","2","mstr_standard","I261";
;
CDS_LIB"mstr_standard"
BODY_TYPE"PLUMBING"
HDL_TAP"TRUE";
"B \NAC \NWC"6;
"S \NAC"
BN"5"64;
%"TAP"
"1","(-5850,5450)","2","mstr_standard","I262";
;
CDS_LIB"mstr_standard"
BODY_TYPE"PLUMBING"
HDL_TAP"TRUE";
"B \NAC \NWC"6;
"S \NAC"
BN"6"63;
%"TAP"
"1","(-5850,5350)","2","mstr_standard","I263";
;
CDS_LIB"mstr_standard"
BODY_TYPE"PLUMBING"
HDL_TAP"TRUE";
"B \NAC \NWC"6;
"S \NAC"
BN"7"62;
%"TAP"
"1","(-5850,5250)","2","mstr_standard","I264";
;
CDS_LIB"mstr_standard"
BODY_TYPE"PLUMBING"
HDL_TAP"TRUE";
"B \NAC \NWC"6;
"S \NAC"
BN"8"61;
%"TAP"
"1","(-5850,5150)","2","mstr_standard","I265";
;
CDS_LIB"mstr_standard"
BODY_TYPE"PLUMBING"
HDL_TAP"TRUE";
"B \NAC \NWC"6;
"S \NAC"
BN"9"60;
%"TAP"
"1","(-6050,5600)","2","mstr_standard","I266";
;
CDS_LIB"mstr_standard"
BODY_TYPE"PLUMBING"
HDL_TAP"TRUE";
"B \NAC \NWC"5;
"S \NAC"
BN"4"74;
%"TAP"
"1","(-6050,5500)","2","mstr_standard","I267";
;
CDS_LIB"mstr_standard"
BODY_TYPE"PLUMBING"
HDL_TAP"TRUE";
"B \NAC \NWC"5;
"S \NAC"
BN"5"72;
%"TAP"
"1","(-6050,5400)","2","mstr_standard","I268";
;
CDS_LIB"mstr_standard"
BODY_TYPE"PLUMBING"
HDL_TAP"TRUE";
"B \NAC \NWC"5;
"S \NAC"
BN"6"70;
%"TAP"
"1","(-6050,5300)","2","mstr_standard","I269";
;
CDS_LIB"mstr_standard"
BODY_TYPE"PLUMBING"
HDL_TAP"TRUE";
"B \NAC \NWC"5;
"S \NAC"
BN"7"68;
%"TAP"
"1","(-6050,5200)","2","mstr_standard","I270";
;
CDS_LIB"mstr_standard"
BODY_TYPE"PLUMBING"
HDL_TAP"TRUE";
"B \NAC \NWC"5;
"S \NAC"
BN"8"66;
%"TAP"
"1","(-5850,5000)","2","mstr_standard","I271";
;
CDS_LIB"mstr_standard"
BODY_TYPE"PLUMBING"
HDL_TAP"TRUE";
"B \NAC \NWC"7;
"S \NAC"
BN"0"49;
%"TAP"
"1","(-5850,4900)","2","mstr_standard","I272";
;
CDS_LIB"mstr_standard"
BODY_TYPE"PLUMBING"
HDL_TAP"TRUE";
"B \NAC \NWC"7;
"S \NAC"
BN"1"47;
%"TAP"
"1","(-5850,4800)","2","mstr_standard","I273";
;
CDS_LIB"mstr_standard"
BODY_TYPE"PLUMBING"
HDL_TAP"TRUE";
"B \NAC \NWC"7;
"S \NAC"
BN"2"45;
%"TAP"
"1","(-5850,4700)","2","mstr_standard","I274";
;
CDS_LIB"mstr_standard"
BODY_TYPE"PLUMBING"
HDL_TAP"TRUE";
"B \NAC \NWC"7;
"S \NAC"
BN"3"43;
%"TAP"
"1","(-6050,5100)","2","mstr_standard","I275";
;
CDS_LIB"mstr_standard"
BODY_TYPE"PLUMBING"
HDL_TAP"TRUE";
"B \NAC \NWC"5;
"S \NAC"
BN"9"51;
%"TAP"
"1","(-6050,4950)","2","mstr_standard","I276";
;
CDS_LIB"mstr_standard"
BODY_TYPE"PLUMBING"
HDL_TAP"TRUE";
"B \NAC \NWC"8;
"S \NAC"
BN"0"55;
%"TAP"
"1","(-6050,4850)","2","mstr_standard","I277";
;
CDS_LIB"mstr_standard"
BODY_TYPE"PLUMBING"
HDL_TAP"TRUE";
"B \NAC \NWC"8;
"S \NAC"
BN"1"54;
%"TAP"
"1","(-6050,4750)","2","mstr_standard","I278";
;
CDS_LIB"mstr_standard"
BODY_TYPE"PLUMBING"
HDL_TAP"TRUE";
"B \NAC \NWC"8;
"S \NAC"
BN"2"53;
%"TAP"
"1","(-6050,4650)","2","mstr_standard","I279";
;
CDS_LIB"mstr_standard"
BODY_TYPE"PLUMBING"
HDL_TAP"TRUE";
"B \NAC \NWC"8;
"S \NAC"
BN"3"52;
%"TAP"
"1","(-5850,4600)","2","mstr_standard","I280";
;
CDS_LIB"mstr_standard"
BODY_TYPE"PLUMBING"
HDL_TAP"TRUE";
"B \NAC \NWC"7;
"S \NAC"
BN"4"41;
%"TAP"
"1","(-5850,4500)","2","mstr_standard","I281";
;
CDS_LIB"mstr_standard"
BODY_TYPE"PLUMBING"
HDL_TAP"TRUE";
"B \NAC \NWC"7;
"S \NAC"
BN"5"59;
%"TAP"
"1","(-5850,4400)","2","mstr_standard","I282";
;
CDS_LIB"mstr_standard"
BODY_TYPE"PLUMBING"
HDL_TAP"TRUE";
"B \NAC \NWC"7;
"S \NAC"
BN"6"58;
%"TAP"
"1","(-5850,4300)","2","mstr_standard","I283";
;
CDS_LIB"mstr_standard"
BODY_TYPE"PLUMBING"
HDL_TAP"TRUE";
"B \NAC \NWC"7;
"S \NAC"
BN"7"57;
%"TAP"
"1","(-5850,4200)","2","mstr_standard","I284";
;
CDS_LIB"mstr_standard"
BODY_TYPE"PLUMBING"
HDL_TAP"TRUE";
"B \NAC \NWC"7;
"S \NAC"
BN"8"56;
%"TAP"
"1","(-5850,4100)","2","mstr_standard","I285";
;
CDS_LIB"mstr_standard"
BODY_TYPE"PLUMBING"
HDL_TAP"TRUE";
"B \NAC \NWC"7;
"S \NAC"
BN"9"40;
%"TAP"
"1","(-6050,4550)","2","mstr_standard","I286";
;
CDS_LIB"mstr_standard"
BODY_TYPE"PLUMBING"
HDL_TAP"TRUE";
"B \NAC \NWC"8;
"S \NAC"
BN"4"50;
%"TAP"
"1","(-6050,4450)","2","mstr_standard","I287";
;
CDS_LIB"mstr_standard"
BODY_TYPE"PLUMBING"
HDL_TAP"TRUE";
"B \NAC \NWC"8;
"S \NAC"
BN"5"48;
%"TAP"
"1","(-6050,4350)","2","mstr_standard","I288";
;
CDS_LIB"mstr_standard"
BODY_TYPE"PLUMBING"
HDL_TAP"TRUE";
"B \NAC \NWC"8;
"S \NAC"
BN"6"46;
%"TAP"
"1","(-6050,4250)","2","mstr_standard","I289";
;
CDS_LIB"mstr_standard"
BODY_TYPE"PLUMBING"
HDL_TAP"TRUE";
"B \NAC \NWC"8;
"S \NAC"
BN"7"44;
%"TAP"
"1","(-6050,4150)","2","mstr_standard","I290";
;
CDS_LIB"mstr_standard"
BODY_TYPE"PLUMBING"
HDL_TAP"TRUE";
"B \NAC \NWC"8;
"S \NAC"
BN"8"42;
%"TAP"
"1","(-6050,4050)","2","mstr_standard","I295";
;
CDS_LIB"mstr_standard"
BODY_TYPE"PLUMBING"
HDL_TAP"TRUE";
"B \NAC \NWC"8;
"S \NAC"
BN"9"39;
%"TAP"
"1","(-6050,3900)","2","mstr_standard","I296";
;
CDS_LIB"mstr_standard"
BODY_TYPE"PLUMBING"
HDL_TAP"TRUE";
"B \NAC \NWC"9;
"S \NAC"
BN"0"38;
%"TAP"
"1","(-6050,3850)","2","mstr_standard","I297";
;
CDS_LIB"mstr_standard"
BODY_TYPE"PLUMBING"
HDL_TAP"TRUE";
"B \NAC \NWC"9;
"S \NAC"
BN"1"36;
%"TAP"
"1","(-6050,3800)","2","mstr_standard","I298";
;
CDS_LIB"mstr_standard"
BODY_TYPE"PLUMBING"
HDL_TAP"TRUE";
"B \NAC \NWC"9;
"S \NAC"
BN"2"34;
%"TAP"
"1","(-6050,3750)","2","mstr_standard","I299";
;
CDS_LIB"mstr_standard"
BODY_TYPE"PLUMBING"
HDL_TAP"TRUE";
"B \NAC \NWC"9;
"S \NAC"
BN"3"32;
%"TAP"
"1","(-6050,3700)","2","mstr_standard","I300";
;
CDS_LIB"mstr_standard"
BODY_TYPE"PLUMBING"
HDL_TAP"TRUE";
"B \NAC \NWC"9;
"S \NAC"
BN"4"30;
%"TAP"
"1","(-6050,3650)","2","mstr_standard","I301";
;
CDS_LIB"mstr_standard"
BODY_TYPE"PLUMBING"
HDL_TAP"TRUE";
"B \NAC \NWC"9;
"S \NAC"
BN"5"28;
%"TAP"
"1","(-6050,3600)","2","mstr_standard","I302";
;
CDS_LIB"mstr_standard"
BODY_TYPE"PLUMBING"
HDL_TAP"TRUE";
"B \NAC \NWC"9;
"S \NAC"
BN"6"26;
%"TAP"
"1","(-6050,3500)","2","mstr_standard","I303";
;
CDS_LIB"mstr_standard"
BODY_TYPE"PLUMBING"
HDL_TAP"TRUE";
"B \NAC \NWC"10;
"S \NAC"
BN"0"37;
%"TAP"
"1","(-6050,3450)","2","mstr_standard","I304";
;
CDS_LIB"mstr_standard"
BODY_TYPE"PLUMBING"
HDL_TAP"TRUE";
"B \NAC \NWC"10;
"S \NAC"
BN"1"35;
%"TAP"
"1","(-6050,3400)","2","mstr_standard","I305";
;
CDS_LIB"mstr_standard"
BODY_TYPE"PLUMBING"
HDL_TAP"TRUE";
"B \NAC \NWC"10;
"S \NAC"
BN"2"33;
%"TAP"
"1","(-6050,3350)","2","mstr_standard","I306";
;
CDS_LIB"mstr_standard"
BODY_TYPE"PLUMBING"
HDL_TAP"TRUE";
"B \NAC \NWC"10;
"S \NAC"
BN"3"31;
%"TAP"
"1","(-6050,3300)","2","mstr_standard","I307";
;
CDS_LIB"mstr_standard"
BODY_TYPE"PLUMBING"
HDL_TAP"TRUE";
"B \NAC \NWC"10;
"S \NAC"
BN"4"29;
%"TAP"
"1","(-6050,3250)","2","mstr_standard","I308";
;
CDS_LIB"mstr_standard"
BODY_TYPE"PLUMBING"
HDL_TAP"TRUE";
"B \NAC \NWC"10;
"S \NAC"
BN"5"27;
%"TAP"
"1","(-6050,3200)","2","mstr_standard","I309";
;
CDS_LIB"mstr_standard"
BODY_TYPE"PLUMBING"
HDL_TAP"TRUE";
"B \NAC \NWC"10;
"S \NAC"
BN"6"25;
%"Q_RES"
"1","(-6725,2200)","0","pure_quanta","I322";
;
LOCATION"R506"
$SEC"1"
CDS_SEC"1"
PACK_TYPE"0402LF"
TOLERANCE"1%"
VALUE"15"
MATERIAL"CHIP"
WATTAGE"1/16W"
CDS_LIB"pure_quanta"
PART_NUMBER"CS01502FB03";
"B"
$PN"2"12;
"A"
$PN"1"11;
END.
